# BASEBOARD_FAB2 (Tioga Pass) — schematic netlist excerpt (pin names and nets, part order shuffled) for the footprints in the layout excerpt that follows; sources: Cadence DE-HDL packaged netlist, KiCad conversion of Wiwynn_Tioga_Pass_MB.brd

EU8A1  PXE1110B  IC  pkg QFN  page 235
  DNC(0)  = NC
  DNC(1)  = NC
  BPWM1  = VR_P1V05_PCH_STBY_PWM1
  DNC(2)  = NC
  APWM1  = VR_PVNN_PCH_PWM1
  SDA  = SMB_VR_STBY_LVC3_SDA
  SCL  = SMB_VR_STBY_LVC3_SCL
  RESET_N  = NC
  AVRRDY  = PWRGD_PVNN_PCH_R
  AVREN  = VR_PVNN_PCH_VREN
  VRHOT_N  = IRQ_PVNN_PCH_VRHOT_N
  PINALRT_N  = PU_PVNN_PCH_PINALRT_N
  MP0  = VID_PCH_CORE_PVNN_AUX_VID_0
  MP1  = VID_PCH_CORE_PVNN_AUX_VID_1
  VCLK  = PU_PVNN_PCH_VCLK
  VDIO  = PU_PVNN_PCH_VDIO
  VALRT_N  = NC
  MP2  = NC
  AVSEN  = VR_PVNN_PCH_AVSP
  AVREF  = VSENSE_PVNN_PCH_STBY_AVSN
  AIREF1  = VR_PVNN_PCH_AIREF1
  AISEN1  = ISENSE_PVNN_PCH_PH1_IMON
  GND(1)  = GND
  DNC(3)  = NC
  BIREF1  = VR_P1V05_PCH_BIREF1
  BISEN1  = ISENSE_P1V05_PCH_STBY_PH1_IMON
  GND(0)  = GND
  DNC(4)  = NC
  BVSEN  = VR_P1V05_PCH_STBY_AVSP
  BVREF  = VSENSE_P1V05_PCH_STBY_AVSN
  MP3  = NC
  MP4  = PU_VR_PVNN_PCH_FAULT1
  XADDR2  = VR_PVNN_PCH_XADDR2
  BTSEN  = A_TSENSE_P1V05_PCH_STBY_TMON
  ATSEN  = A_TSENSE_PVNN_PCH_TMON
  XADDR1  = VR_PVNN_PCH_XADDR1
  VINSEN  = VR_PVNN_PCH_VINSEN
  IINSEN  = NC
  VDD  = VR_PVNN_PCH_VDD
  VD12  = VR_PVNN_P1V05_PCH_VD12
  THPAD  = GND

(kicad_pcb
	(version 20260206)
	(generator "pcbnew")
	(generator_version "10.0")
	(general
		(thickness 1.6)
		(legacy_teardrops no)
	)
	(paper "A4")
	(title_block
		(title "Wiwynn_Tioga_Pass_MB.brd")
		(comment 1 "Tioga Pass / footprint 1719 of 4770 (EU8A1), pads 35-41 of 41")
	)
	(layers
		(0 "F.Cu" signal "TOP")
		(4 "In1.Cu" signal "L2GND")
		(6 "In2.Cu" signal "L3")
		(8 "In3.Cu" signal "L4GND")
		(10 "In4.Cu" signal "L5")
		(12 "In5.Cu" signal "L6GND")
		(14 "In6.Cu" signal "L7VCC")
		(16 "In7.Cu" signal "L8VCC")
		(18 "In8.Cu" signal "L9GND")
		(20 "In9.Cu" signal "L10")
		(22 "In10.Cu" signal "L11GND")
		(24 "In11.Cu" signal "L12")
		(26 "In12.Cu" signal "L13GND")
		(2 "B.Cu" signal "BOTTOM")
		(9 "F.Adhes" user "F.Adhesive")
		(11 "B.Adhes" user "B.Adhesive")
		(13 "F.Paste" user "Package Geometry/Pastemask Top")
		(15 "B.Paste" user "Package Geometry/Pastemask Bottom")
		(5 "F.SilkS" user "Ref Des/Silkscreen Top")
		(7 "B.SilkS" user "Ref Des/Silkscreen Bottom")
		(1 "F.Mask" user "Board Geometry/Soldermask Top")
		(3 "B.Mask" user "Board Geometry/Soldermask Bottom")
		(17 "Dwgs.User" user "User.Drawings")
		(19 "Cmts.User" user "User.Comments")
		(21 "Eco1.User" user "User.Eco1")
		(23 "Eco2.User" user "User.Eco2")
		(25 "Edge.Cuts" user "Board Geometry/Outline")
		(27 "Margin" user)
		(31 "F.CrtYd" user "Package Geometry/Place Bound Top")
		(29 "B.CrtYd" user "Package Geometry/Place Bound Bottom")
		(35 "F.Fab" user "Ref Des/Assembly Top")
		(33 "B.Fab" user "Ref Des/Assembly Bottom")
	)
	(footprint ""
		(layer "F.Cu")
		(at 395.7828 -153.797 90)
		(property "Reference" "EU8A1"
			(at 3.40233 -2.7178 0)
			(unlocked yes)
			(layer "F.SilkS")
			(effects
				(font
					(size 0.7874 0.5842)
					(thickness 0.1524)
				)
				(justify left)
			)
		)
		(property "Value" ""
			(at 0 0 90)
			(layer "F.Fab")
			(effects
				(font
					(size 1.27 1.27)
				)
			)
		)
		(duplicate_pad_numbers_are_jumpers no)
		(pad "35" smd custom
			(at 0.199898 -2.4511 90)
			(size 0.0508 0.0508)
			(layers "F.Cu" "F.Mask" "F.Paste")
			(net "A_TSENSE_PVNN_PCH_TMON")
			(options
				(clearance outline)
				(anchor circle)
			)
			(primitives
				(gr_poly
					(pts
						(arc
							(start 0.1016 0.254)
							(mid 0 0.3556)
							(end -0.1016 0.254)
						)
						(xy -0.1016 -0.3556) (xy 0.1016 -0.3556)
					)
					(width 0)
					(fill yes)
				)
			)
		)
		(pad "36" smd custom
			(at -0.199898 -2.4511 90)
			(size 0.0508 0.0508)
			(layers "F.Cu" "F.Mask" "F.Paste")
			(net "VR_PVNN_PCH_XADDR1")
			(options
				(clearance outline)
				(anchor circle)
			)
			(primitives
				(gr_poly
					(pts
						(arc
							(start 0.1016 0.254)
							(mid 0 0.3556)
							(end -0.1016 0.254)
						)
						(xy -0.1016 -0.3556) (xy 0.1016 -0.3556)
					)
					(width 0)
					(fill yes)
				)
			)
		)
		(pad "37" smd custom
			(at -0.599948 -2.4511 90)
			(size 0.0508 0.0508)
			(layers "F.Cu" "F.Mask" "F.Paste")
			(net "VR_PVNN_PCH_VINSEN")
			(options
				(clearance outline)
				(anchor circle)
			)
			(primitives
				(gr_poly
					(pts
						(arc
							(start 0.1016 0.254)
							(mid 0 0.3556)
							(end -0.1016 0.254)
						)
						(xy -0.1016 -0.3556) (xy 0.1016 -0.3556)
					)
					(width 0)
					(fill yes)
				)
			)
		)
		(pad "38" smd custom
			(at -0.999998 -2.4511 90)
			(size 0.0508 0.0508)
			(layers "F.Cu" "F.Mask" "F.Paste")
			(net "Net_268")
			(options
				(clearance outline)
				(anchor circle)
			)
			(primitives
				(gr_poly
					(pts
						(arc
							(start 0.1016 0.254)
							(mid 0 0.3556)
							(end -0.1016 0.254)
						)
						(xy -0.1016 -0.3556) (xy 0.1016 -0.3556)
					)
					(width 0)
					(fill yes)
				)
			)
		)
		(pad "39" smd custom
			(at -1.400048 -2.4511 90)
			(size 0.0508 0.0508)
			(layers "F.Cu" "F.Mask" "F.Paste")
			(net "VR_PVNN_PCH_VDD")
			(options
				(clearance outline)
				(anchor circle)
			)
			(primitives
				(gr_poly
					(pts
						(arc
							(start 0.1016 0.254)
							(mid 0 0.3556)
							(end -0.1016 0.254)
						)
						(xy -0.1016 -0.3556) (xy 0.1016 -0.3556)
					)
					(width 0)
					(fill yes)
				)
			)
		)
		(pad "40" smd custom
			(at -1.800098 -2.4511 90)
			(size 0.0508 0.0508)
			(layers "F.Cu" "F.Mask" "F.Paste")
			(net "VR_PVNN_P1V05_PCH_VD12")
			(options
				(clearance outline)
				(anchor circle)
			)
			(primitives
				(gr_poly
					(pts
						(arc
							(start 0.1016 0.254)
							(mid 0 0.3556)
							(end -0.1016 0.254)
						)
						(xy -0.1016 -0.3556) (xy 0.1016 -0.3556)
					)
					(width 0)
					(fill yes)
				)
			)
		)
		(pad "41" smd rect
			(at 0 0 90)
			(size 3.683 3.683)
			(layers "F.Cu" "F.Mask" "F.Paste")
			(net "GND")
		)
	)
)
